(kicad_pcb
	(version 20260206)
	(generator "pcbnew")
	(generator_version "10.0")
	(general
		(thickness 1.6)
		(legacy_teardrops no)
	)
	(paper "A4")
	(title_block
		(title "panther-plus-userver — 13130-1b_20150205.brd")
		(comment 1 "Honey Badger (Wiwynn) / footprints 1505-1509 of 1509")
	)
	(layers
		(0 "F.Cu" signal "TOP")
		(4 "In1.Cu" signal "L2")
		(6 "In2.Cu" signal "L3")
		(8 "In3.Cu" signal "L4")
		(10 "In4.Cu" signal "L5")
		(12 "In5.Cu" signal "L6")
		(14 "In6.Cu" signal "L7")
		(16 "In7.Cu" signal "L8")
		(18 "In8.Cu" signal "L9")
		(20 "In9.Cu" signal "L10")
		(22 "In10.Cu" signal "L11")
		(2 "B.Cu" signal "BOTTOM")
		(9 "F.Adhes" user "F.Adhesive")
		(11 "B.Adhes" user "B.Adhesive")
		(13 "F.Paste" user "Package Geometry/Pastemask Top")
		(15 "B.Paste" user "Package Geometry/Pastemask Bottom")
		(5 "F.SilkS" user "Ref Des/Silkscreen Top")
		(7 "B.SilkS" user "Ref Des/Silkscreen Bottom")
		(1 "F.Mask" user "Board Geometry/Soldermask Top")
		(3 "B.Mask" user "Board Geometry/Soldermask Bottom")
		(17 "Dwgs.User" user "User.Drawings")
		(19 "Cmts.User" user "User.Comments")
		(21 "Eco1.User" user "User.Eco1")
		(23 "Eco2.User" user "User.Eco2")
		(25 "Edge.Cuts" user "Board Geometry/Outline")
		(27 "Margin" user)
		(31 "F.CrtYd" user "Package Geometry/Place Bound Top")
		(29 "B.CrtYd" user "Package Geometry/Place Bound Bottom")
		(35 "F.Fab" user "Ref Des/Assembly Top")
		(33 "B.Fab" user "Ref Des/Assembly Bottom")
	)
	(footprint ""
		(layer "B.Cu")
		(at 156.9212 -59.6646)
		(property "Reference" "C99"
			(at 0 0 0)
			(layer "B.SilkS")
			(hide yes)
			(effects
				(font
					(size 1.27 1.27)
				)
				(justify mirror)
			)
		)
		(property "Value" "SC1U10V2KX-1GP"
			(at -1.8923 -1.2065 0)
			(unlocked yes)
			(layer "B.Fab")
			(hide yes)
			(effects
				(font
					(size 1.016 1.016)
					(thickness 0.1524)
				)
				(justify mirror)
			)
		)
		(property "Device Type" "C402H22"
			(at -1.8923 -2.7305 0)
			(unlocked yes)
			(layer "B.Fab")
			(hide yes)
			(effects
				(font
					(size 1.016 1.016)
					(thickness 0.1524)
				)
				(justify mirror)
			)
		)
		(duplicate_pad_numbers_are_jumpers no)
		(fp_rect
			(start 0.381 0.7366)
			(end -0.381 -0.7366)
			(stroke
				(width 0)
				(type default)
			)
			(fill no)
			(layer "B.CrtYd")
		)
		(fp_rect
			(start 0.381 0.7366)
			(end -0.381 -0.7366)
			(stroke
				(width 0)
				(type default)
			)
			(fill no)
			(layer "B.Fab")
		)
		(pad "1" smd custom
			(at 0 -0.4572 180)
			(size 0.1143 0.1143)
			(layers "B.Cu" "B.Mask" "B.Paste")
			(net "PV_VDDR")
			(options
				(clearance outline)
				(anchor circle)
			)
			(primitives
				(gr_poly
					(pts
						(arc
							(start -0.254 0.1778)
							(mid -0.239121 0.213721)
							(end -0.2032 0.2286)
						)
						(arc
							(start 0.2032 0.2286)
							(mid 0.239121 0.213721)
							(end 0.254 0.1778)
						)
						(arc
							(start 0.254 -0.1778)
							(mid 0.239121 -0.213721)
							(end 0.2032 -0.2286)
						)
						(arc
							(start -0.2032 -0.2286)
							(mid -0.239121 -0.213721)
							(end -0.254 -0.1778)
						)
					)
					(width 0)
					(fill yes)
				)
			)
		)
		(pad "2" smd custom
			(at 0 0.4572 180)
			(size 0.1143 0.1143)
			(layers "B.Cu" "B.Mask" "B.Paste")
			(net "GND")
			(options
				(clearance outline)
				(anchor circle)
			)
			(primitives
				(gr_poly
					(pts
						(arc
							(start -0.254 0.1778)
							(mid -0.239121 0.213721)
							(end -0.2032 0.2286)
						)
						(arc
							(start 0.2032 0.2286)
							(mid 0.239121 0.213721)
							(end 0.254 0.1778)
						)
						(arc
							(start 0.254 -0.1778)
							(mid 0.239121 -0.213721)
							(end 0.2032 -0.2286)
						)
						(arc
							(start -0.2032 -0.2286)
							(mid -0.239121 -0.213721)
							(end -0.254 -0.1778)
						)
					)
					(width 0)
					(fill yes)
				)
			)
		)
	)
	(footprint ""
		(layer "B.Cu")
		(at 197.104 -70.104 -90)
		(property "Reference" "Q13"
			(at 0 0 90)
			(layer "B.SilkS")
			(hide yes)
			(effects
				(font
					(size 1.27 1.27)
				)
				(justify mirror)
			)
		)
		(property "Value" "2N7002A-7-GP"
			(at 4.3561 -5.7912 270)
			(unlocked yes)
			(layer "B.Fab")
			(hide yes)
			(effects
				(font
					(size 1.016 1.016)
					(thickness 0.1524)
				)
				(justify mirror)
			)
		)
		(property "Device Type" "SOT23DGS2D4H48"
			(at 4.3561 -7.3152 270)
			(unlocked yes)
			(layer "B.Fab")
			(hide yes)
			(effects
				(font
					(size 1.016 1.016)
					(thickness 0.1524)
				)
				(justify mirror)
			)
		)
		(duplicate_pad_numbers_are_jumpers no)
		(fp_line
			(start -1.7145 0.4445)
			(end -1.7145 -0.4445)
			(stroke
				(width 0.1524)
				(type default)
			)
			(layer "B.SilkS")
		)
		(fp_line
			(start 1.7145 0.4445)
			(end -1.7145 0.4445)
			(stroke
				(width 0.1524)
				(type default)
			)
			(layer "B.SilkS")
		)
		(fp_line
			(start -1.7145 -0.4445)
			(end 1.7145 -0.4445)
			(stroke
				(width 0.1524)
				(type default)
			)
			(layer "B.SilkS")
		)
		(fp_line
			(start 1.7145 -0.4445)
			(end 1.7145 0.4445)
			(stroke
				(width 0.1524)
				(type default)
			)
			(layer "B.SilkS")
		)
		(fp_poly
			(pts
				(xy 1.4224 1.5621) (xy 1.4224 0.9017) (xy 1.7145 0.9017) (xy 1.7145 -0.9017) (xy 0.4699 -0.9017)
				(xy 0.4699 -1.5621) (xy -0.4699 -1.5621) (xy -0.4699 -0.9017) (xy -1.7145 -0.9017) (xy -1.7145 0.9017)
				(xy -1.4224 0.9017) (xy -1.4224 1.5621) (xy -0.4826 1.5621) (xy -0.4826 0.9017) (xy 0.4826 0.9017)
				(xy 0.4826 1.5621)
			)
			(stroke
				(width 0)
				(type default)
			)
			(fill no)
			(layer "B.CrtYd")
		)
		(fp_poly
			(pts
				(xy 1.4224 1.5621) (xy 1.4224 0.9017) (xy 1.7145 0.9017) (xy 1.7145 -0.9017) (xy 0.4699 -0.9017)
				(xy 0.4699 -1.5621) (xy -0.4699 -1.5621) (xy -0.4699 -0.9017) (xy -1.7145 -0.9017) (xy -1.7145 0.9017)
				(xy -1.4224 0.9017) (xy -1.4224 1.5621) (xy -0.4826 1.5621) (xy -0.4826 0.9017) (xy 0.4826 0.9017)
				(xy 0.4826 1.5621)
			)
			(stroke
				(width 0)
				(type default)
			)
			(fill no)
			(layer "B.Fab")
		)
		(pad "D" smd custom
			(at 0 -1.069086 90)
			(size 0.17145 0.17145)
			(layers "B.Cu" "B.Mask" "B.Paste")
			(net "PWR_STATUS_LED_D")
			(options
				(clearance outline)
				(anchor circle)
			)
			(primitives
				(gr_poly
					(pts
						(arc
							(start -0.1397 -0.3683)
							(mid -0.283384 -0.308784)
							(end -0.3429 -0.1651)
						)
						(arc
							(start -0.3429 0.1651)
							(mid -0.283384 0.308784)
							(end -0.1397 0.3683)
						)
						(arc
							(start 0.1397 0.3683)
							(mid 0.283384 0.308784)
							(end 0.3429 0.1651)
						)
						(arc
							(start 0.3429 -0.1651)
							(mid 0.283384 -0.308784)
							(end 0.1397 -0.3683)
						)
					)
					(width 0)
					(fill yes)
				)
			)
		)
		(pad "G" smd custom
			(at 0.94996 1.069086 90)
			(size 0.17145 0.17145)
			(layers "B.Cu" "B.Mask" "B.Paste")
			(net "PWR_STATUS_LED_EN")
			(options
				(clearance outline)
				(anchor circle)
			)
			(primitives
				(gr_poly
					(pts
						(arc
							(start -0.1397 -0.3683)
							(mid -0.283384 -0.308784)
							(end -0.3429 -0.1651)
						)
						(arc
							(start -0.3429 0.1651)
							(mid -0.283384 0.308784)
							(end -0.1397 0.3683)
						)
						(arc
							(start 0.1397 0.3683)
							(mid 0.283384 0.308784)
							(end 0.3429 0.1651)
						)
						(arc
							(start 0.3429 -0.1651)
							(mid 0.283384 -0.308784)
							(end 0.1397 -0.3683)
						)
					)
					(width 0)
					(fill yes)
				)
			)
		)
		(pad "S" smd custom
			(at -0.94996 1.069086 90)
			(size 0.17145 0.17145)
			(layers "B.Cu" "B.Mask" "B.Paste")
			(net "GND")
			(options
				(clearance outline)
				(anchor circle)
			)
			(primitives
				(gr_poly
					(pts
						(arc
							(start -0.1397 -0.3683)
							(mid -0.283384 -0.308784)
							(end -0.3429 -0.1651)
						)
						(arc
							(start -0.3429 0.1651)
							(mid -0.283384 0.308784)
							(end -0.1397 0.3683)
						)
						(arc
							(start 0.1397 0.3683)
							(mid 0.283384 0.308784)
							(end 0.3429 0.1651)
						)
						(arc
							(start 0.3429 -0.1651)
							(mid 0.283384 -0.308784)
							(end 0.1397 -0.3683)
						)
					)
					(width 0)
					(fill yes)
				)
			)
		)
	)
	(footprint ""
		(layer "B.Cu")
		(at 87.58936 -26.07056)
		(property "Reference" "R377"
			(at 0 0 0)
			(layer "B.SilkS")
			(hide yes)
			(effects
				(font
					(size 1.27 1.27)
				)
				(justify mirror)
			)
		)
		(property "Value" "1KR2F-3-GP"
			(at -0.064008 -3.993896 0)
			(unlocked yes)
			(layer "B.Fab")
			(hide yes)
			(effects
				(font
					(size 1.016 1.016)
					(thickness 0.1524)
				)
				(justify mirror)
			)
		)
		(property "Device Type" "R402H16"
			(at -0.064008 -5.517896 0)
			(unlocked yes)
			(layer "B.Fab")
			(hide yes)
			(effects
				(font
					(size 1.016 1.016)
					(thickness 0.1524)
				)
				(justify mirror)
			)
		)
		(duplicate_pad_numbers_are_jumpers no)
		(fp_rect
			(start 0.381 0.8382)
			(end -0.381 -0.8382)
			(stroke
				(width 0)
				(type default)
			)
			(fill no)
			(layer "B.CrtYd")
		)
		(fp_rect
			(start 0.381 0.8382)
			(end -0.381 -0.8382)
			(stroke
				(width 0)
				(type default)
			)
			(fill no)
			(layer "B.Fab")
		)
		(pad "1" smd custom
			(at 0 -0.4318 180)
			(size 0.127 0.127)
			(layers "B.Cu" "B.Mask" "B.Paste")
			(net "BD_REV_0")
			(options
				(clearance outline)
				(anchor circle)
			)
			(primitives
				(gr_poly
					(pts
						(arc
							(start -0.2032 0.2794)
							(mid -0.239121 0.264521)
							(end -0.254 0.2286)
						)
						(arc
							(start -0.254 -0.2286)
							(mid -0.239121 -0.264521)
							(end -0.2032 -0.2794)
						)
						(arc
							(start 0.2032 -0.2794)
							(mid 0.239121 -0.264521)
							(end 0.254 -0.2286)
						)
						(arc
							(start 0.254 0.2286)
							(mid 0.239121 0.264521)
							(end 0.2032 0.2794)
						)
					)
					(width 0)
					(fill yes)
				)
			)
		)
		(pad "2" smd custom
			(at 0 0.4318 180)
			(size 0.127 0.127)
			(layers "B.Cu" "B.Mask" "B.Paste")
			(net "GND")
			(options
				(clearance outline)
				(anchor circle)
			)
			(primitives
				(gr_poly
					(pts
						(arc
							(start -0.2032 0.2794)
							(mid -0.239121 0.264521)
							(end -0.254 0.2286)
						)
						(arc
							(start -0.254 -0.2286)
							(mid -0.239121 -0.264521)
							(end -0.2032 -0.2794)
						)
						(arc
							(start 0.2032 -0.2794)
							(mid 0.239121 -0.264521)
							(end 0.254 -0.2286)
						)
						(arc
							(start 0.254 0.2286)
							(mid 0.239121 0.264521)
							(end 0.2032 0.2794)
						)
					)
					(width 0)
					(fill yes)
				)
			)
		)
	)
	(footprint ""
		(layer "B.Cu")
		(at 90.424 -43.2562 180)
		(property "Reference" "R47"
			(at 0 0 0)
			(layer "B.SilkS")
			(hide yes)
			(effects
				(font
					(size 1.27 1.27)
				)
				(justify mirror)
			)
		)
		(property "Value" "51R2F-2-GP"
			(at -0.064008 -3.993896 180)
			(unlocked yes)
			(layer "B.Fab")
			(hide yes)
			(effects
				(font
					(size 1.016 1.016)
					(thickness 0.1524)
				)
				(justify mirror)
			)
		)
		(property "Device Type" "R402H16"
			(at -0.064008 -5.517896 180)
			(unlocked yes)
			(layer "B.Fab")
			(hide yes)
			(effects
				(font
					(size 1.016 1.016)
					(thickness 0.1524)
				)
				(justify mirror)
			)
		)
		(duplicate_pad_numbers_are_jumpers no)
		(fp_rect
			(start 0.381 0.8382)
			(end -0.381 -0.8382)
			(stroke
				(width 0)
				(type default)
			)
			(fill no)
			(layer "B.CrtYd")
		)
		(fp_rect
			(start 0.381 0.8382)
			(end -0.381 -0.8382)
			(stroke
				(width 0)
				(type default)
			)
			(fill no)
			(layer "B.Fab")
		)
		(pad "1" smd custom
			(at 0 -0.4318)
			(size 0.127 0.127)
			(layers "B.Cu" "B.Mask" "B.Paste")
			(net "CTBTRIGINOUT")
			(options
				(clearance outline)
				(anchor circle)
			)
			(primitives
				(gr_poly
					(pts
						(arc
							(start -0.2032 0.2794)
							(mid -0.239121 0.264521)
							(end -0.254 0.2286)
						)
						(arc
							(start -0.254 -0.2286)
							(mid -0.239121 -0.264521)
							(end -0.2032 -0.2794)
						)
						(arc
							(start 0.2032 -0.2794)
							(mid 0.239121 -0.264521)
							(end 0.254 -0.2286)
						)
						(arc
							(start 0.254 0.2286)
							(mid 0.239121 0.264521)
							(end 0.2032 0.2794)
						)
					)
					(width 0)
					(fill yes)
				)
			)
		)
		(pad "2" smd custom
			(at 0 0.4318)
			(size 0.127 0.127)
			(layers "B.Cu" "B.Mask" "B.Paste")
			(net "GND")
			(options
				(clearance outline)
				(anchor circle)
			)
			(primitives
				(gr_poly
					(pts
						(arc
							(start -0.2032 0.2794)
							(mid -0.239121 0.264521)
							(end -0.254 0.2286)
						)
						(arc
							(start -0.254 -0.2286)
							(mid -0.239121 -0.264521)
							(end -0.2032 -0.2794)
						)
						(arc
							(start 0.2032 -0.2794)
							(mid 0.239121 -0.264521)
							(end 0.254 -0.2286)
						)
						(arc
							(start 0.254 0.2286)
							(mid 0.239121 0.264521)
							(end 0.2032 0.2794)
						)
					)
					(width 0)
					(fill yes)
				)
			)
		)
	)
	(footprint ""
		(layer "B.Cu")
		(at 110.617 -47.879 90)
		(property "Reference" "C142"
			(at 0 0 90)
			(layer "B.SilkS")
			(hide yes)
			(effects
				(font
					(size 1.27 1.27)
				)
				(justify mirror)
			)
		)
		(property "Value" "SC1U10V2KX-1GP"
			(at -1.1811 -2.7051 90)
			(unlocked yes)
			(layer "B.Fab")
			(hide yes)
			(effects
				(font
					(size 1.016 1.016)
					(thickness 0.1524)
				)
				(justify mirror)
			)
		)
		(property "Device Type" "C402H22"
			(at -1.1811 -4.2291 90)
			(unlocked yes)
			(layer "B.Fab")
			(hide yes)
			(effects
				(font
					(size 1.016 1.016)
					(thickness 0.1524)
				)
				(justify mirror)
			)
		)
		(duplicate_pad_numbers_are_jumpers no)
		(fp_rect
			(start 0.381 0.7366)
			(end -0.381 -0.7366)
			(stroke
				(width 0)
				(type default)
			)
			(fill no)
			(layer "B.CrtYd")
		)
		(fp_rect
			(start 0.381 0.7366)
			(end -0.381 -0.7366)
			(stroke
				(width 0)
				(type default)
			)
			(fill no)
			(layer "B.Fab")
		)
		(pad "1" smd custom
			(at 0 -0.4572 270)
			(size 0.1143 0.1143)
			(layers "B.Cu" "B.Mask" "B.Paste")
			(net "PV_VDDR")
			(options
				(clearance outline)
				(anchor circle)
			)
			(primitives
				(gr_poly
					(pts
						(arc
							(start -0.254 0.1778)
							(mid -0.239121 0.213721)
							(end -0.2032 0.2286)
						)
						(arc
							(start 0.2032 0.2286)
							(mid 0.239121 0.213721)
							(end 0.254 0.1778)
						)
						(arc
							(start 0.254 -0.1778)
							(mid 0.239121 -0.213721)
							(end 0.2032 -0.2286)
						)
						(arc
							(start -0.2032 -0.2286)
							(mid -0.239121 -0.213721)
							(end -0.254 -0.1778)
						)
					)
					(width 0)
					(fill yes)
				)
			)
		)
		(pad "2" smd custom
			(at 0 0.4572 270)
			(size 0.1143 0.1143)
			(layers "B.Cu" "B.Mask" "B.Paste")
			(net "GND")
			(options
				(clearance outline)
				(anchor circle)
			)
			(primitives
				(gr_poly
					(pts
						(arc
							(start -0.254 0.1778)
							(mid -0.239121 0.213721)
							(end -0.2032 0.2286)
						)
						(arc
							(start 0.2032 0.2286)
							(mid 0.239121 0.213721)
							(end 0.254 0.1778)
						)
						(arc
							(start 0.254 -0.1778)
							(mid 0.239121 -0.213721)
							(end 0.2032 -0.2286)
						)
						(arc
							(start -0.2032 -0.2286)
							(mid -0.239121 -0.213721)
							(end -0.254 -0.1778)
						)
					)
					(width 0)
					(fill yes)
				)
			)
		)
	)
)
